(kicad_pcb
	(version 20241229)
	(generator "pcbnew")
	(generator_version "9.0")
	(general
		(thickness 1.61)
		(legacy_teardrops no)
	)
	(paper "A3")
	(title_block
		(title "SO-DIMM DDR5 Tester")
		(date "2025-11-26")
		(rev "1.3.0")
		(comment 9 "footprints 139-142 of 627")
	)
	(layers
		(0 "F.Cu" signal)
		(4 "In1.Cu" power)
		(6 "In2.Cu" mixed)
		(8 "In3.Cu" power)
		(10 "In4.Cu" mixed)
		(12 "In5.Cu" power)
		(14 "In6.Cu" mixed)
		(16 "In7.Cu" power)
		(18 "In8.Cu" power)
		(20 "In9.Cu" mixed)
		(22 "In10.Cu" power)
		(2 "B.Cu" signal)
		(9 "F.Adhes" user "F.Adhesive")
		(11 "B.Adhes" user "B.Adhesive")
		(13 "F.Paste" user)
		(15 "B.Paste" user)
		(5 "F.SilkS" user "F.Silkscreen")
		(7 "B.SilkS" user "B.Silkscreen")
		(1 "F.Mask" user)
		(3 "B.Mask" user)
		(17 "Dwgs.User" user "User.Drawings")
		(19 "Cmts.User" user "User.Comments")
		(21 "Eco1.User" user "User.Eco1")
		(23 "Eco2.User" user "User.Eco2")
		(25 "Edge.Cuts" user)
		(27 "Margin" user)
		(31 "F.CrtYd" user "F.Courtyard")
		(29 "B.CrtYd" user "B.Courtyard")
		(35 "F.Fab" user)
		(33 "B.Fab" user)
	)
	(footprint "antmicro-footprints:SC70-3"
		(layer "F.Cu")
		(at 94.750501 129.249 90)
		(property "Reference" "Q2"
			(at 0 -1.6 90)
			(layer "F.SilkS")
			(hide yes)
			(effects
				(font
					(size 0.7 0.7)
					(thickness 0.15)
				)
				(justify left bottom)
			)
		)
		(property "Value" "BSS138PW,115"
			(at 0 2.3 90)
			(layer "F.Fab")
			(effects
				(font
					(size 0.7 0.7)
					(thickness 0.15)
				)
				(justify left bottom)
			)
		)
		(property "Datasheet" "https://assets.nexperia.com/documents/data-sheet/BSS138PW.pdf"
			(at 0 0 90)
			(layer "F.Fab")
			(hide yes)
			(effects
				(font
					(size 1.27 1.27)
					(thickness 0.15)
				)
			)
		)
		(property "Description" "Power MOSFET, N Channel, 60 V, 320 mA, 0.9 ohm, SOT-323, Surface Mount"
			(at 0 0 90)
			(layer "F.Fab")
			(hide yes)
			(effects
				(font
					(size 1.27 1.27)
					(thickness 0.15)
				)
			)
		)
		(property "Author" "Antmicro"
			(at 223.999501 34.498499 0)
			(layer "F.Fab")
			(hide yes)
			(effects
				(font
					(size 1 1)
					(thickness 0.15)
				)
			)
		)
		(property "License" "Apache-2.0"
			(at 223.999501 34.498499 0)
			(layer "F.Fab")
			(hide yes)
			(effects
				(font
					(size 1 1)
					(thickness 0.15)
				)
			)
		)
		(property "MPN" "BSS138PW,115"
			(at 223.999501 34.498499 0)
			(layer "F.Fab")
			(hide yes)
			(effects
				(font
					(size 1 1)
					(thickness 0.15)
				)
			)
		)
		(property "Manufacturer" "Nexperia"
			(at 223.999501 34.498499 0)
			(layer "F.Fab")
			(hide yes)
			(effects
				(font
					(size 1 1)
					(thickness 0.15)
				)
			)
		)
		(sheetname "/FPGA Config/")
		(sheetfile "fpga-config.kicad_sch")
		(attr smd)
		(fp_line
			(start -0.3 -1)
			(end 0.627 -0.999)
			(stroke
				(width 0.15)
				(type solid)
			)
			(layer "F.SilkS")
		)
		(fp_line
			(start 0.627 -0.6)
			(end 0.627 -0.999)
			(stroke
				(width 0.15)
				(type solid)
			)
			(layer "F.SilkS")
		)
		(fp_line
			(start 0.627 0.6)
			(end 0.627 1.001)
			(stroke
				(width 0.15)
				(type solid)
			)
			(layer "F.SilkS")
		)
		(fp_line
			(start -0.3 1)
			(end 0.627 1.001)
			(stroke
				(width 0.15)
				(type solid)
			)
			(layer "F.SilkS")
		)
		(fp_line
			(start 0.9 -1.3)
			(end 0.9 -0.4)
			(stroke
				(width 0.05)
				(type solid)
			)
			(layer "F.CrtYd")
		)
		(fp_line
			(start -0.9 -1.3)
			(end 0.9 -1.3)
			(stroke
				(width 0.05)
				(type solid)
			)
			(layer "F.CrtYd")
		)
		(fp_line
			(start -0.9 -1.3)
			(end -0.9 -1)
			(stroke
				(width 0.05)
				(type solid)
			)
			(layer "F.CrtYd")
		)
		(fp_line
			(start -0.9 -1)
			(end -1.4 -1)
			(stroke
				(width 0.05)
				(type solid)
			)
			(layer "F.CrtYd")
		)
		(fp_line
			(start 1.4 -0.4)
			(end 1.4 0.4)
			(stroke
				(width 0.05)
				(type solid)
			)
			(layer "F.CrtYd")
		)
		(fp_line
			(start 0.9 -0.4)
			(end 1.4 -0.4)
			(stroke
				(width 0.05)
				(type solid)
			)
			(layer "F.CrtYd")
		)
		(fp_line
			(start 1.4 0.4)
			(end 0.9 0.4)
			(stroke
				(width 0.05)
				(type solid)
			)
			(layer "F.CrtYd")
		)
		(fp_line
			(start 0.9 0.4)
			(end 0.9 1.3)
			(stroke
				(width 0.05)
				(type solid)
			)
			(layer "F.CrtYd")
		)
		(fp_line
			(start -0.9 1)
			(end -1.4 1)
			(stroke
				(width 0.05)
				(type solid)
			)
			(layer "F.CrtYd")
		)
		(fp_line
			(start -1.4 1)
			(end -1.4 -1)
			(stroke
				(width 0.05)
				(type solid)
			)
			(layer "F.CrtYd")
		)
		(fp_line
			(start 0.9 1.3)
			(end -0.9 1.3)
			(stroke
				(width 0.05)
				(type solid)
			)
			(layer "F.CrtYd")
		)
		(fp_line
			(start -0.9 1.3)
			(end -0.9 1)
			(stroke
				(width 0.05)
				(type solid)
			)
			(layer "F.CrtYd")
		)
		(fp_rect
			(start -0.623 -0.999)
			(end 0.627 1.001)
			(stroke
				(width 0.15)
				(type solid)
			)
			(fill no)
			(layer "F.Fab")
		)
		(pad "1" smd rect
			(at -1.051 -0.65 180)
			(size 0.6 0.6)
			(layers "F.Cu" "F.Mask" "F.Paste")
			(net 613 "/FPGA Config/DONE")
			(pinfunction "G")
			(pintype "input")
		)
		(pad "2" smd rect
			(at -1.051 0.65 180)
			(size 0.6 0.6)
			(layers "F.Cu" "F.Mask" "F.Paste")
			(net 1 "GND")
			(pinfunction "S")
			(pintype "passive")
		)
		(pad "3" smd rect
			(at 1.05 0 180)
			(size 0.6 0.6)
			(layers "F.Cu" "F.Mask" "F.Paste")
			(net 351 "Net-(Q2-D)")
			(pinfunction "D")
			(pintype "passive")
		)
	)
	(footprint "antmicro-footprints:R_0402_1005Metric"
		(layer "F.Cu")
		(at 83.650501 119.926 -90)
		(descr "Resistor SMD 0402")
		(tags "resistor SMD 0402")
		(property "Reference" "R40"
			(at -1.122484 -0.772697 270)
			(layer "F.SilkS")
			(hide yes)
			(effects
				(font
					(size 0.7 0.7)
					(thickness 0.15)
				)
				(justify left bottom)
			)
		)
		(property "Value" "R_330R_0402"
			(at -1.011843 1.772047 270)
			(layer "F.Fab")
			(effects
				(font
					(size 0.7 0.7)
					(thickness 0.15)
				)
				(justify left bottom)
			)
		)
		(property "Datasheet" "https://www.bourns.com/docs/product-datasheets/cr.pdf"
			(at 0 0 270)
			(layer "F.Fab")
			(hide yes)
			(effects
				(font
					(size 1.27 1.27)
					(thickness 0.15)
				)
			)
		)
		(property "Author" "Antmicro"
			(at -36.275499 203.576501 0)
			(layer "F.Fab")
			(hide yes)
			(effects
				(font
					(size 1 1)
					(thickness 0.15)
				)
			)
		)
		(property "License" "Apache-2.0"
			(at -36.275499 203.576501 0)
			(layer "F.Fab")
			(hide yes)
			(effects
				(font
					(size 1 1)
					(thickness 0.15)
				)
			)
		)
		(property "MPN" "CR0402-FX-3300GLF"
			(at -36.275499 203.576501 0)
			(layer "F.Fab")
			(hide yes)
			(effects
				(font
					(size 1 1)
					(thickness 0.15)
				)
			)
		)
		(property "Manufacturer" "Bourns"
			(at -36.275499 203.576501 0)
			(layer "F.Fab")
			(hide yes)
			(effects
				(font
					(size 1 1)
					(thickness 0.15)
				)
			)
		)
		(property "Tolerance" "1%"
			(at -36.275499 203.576501 0)
			(layer "F.Fab")
			(hide yes)
			(effects
				(font
					(size 1 1)
					(thickness 0.15)
				)
			)
		)
		(property "Val" "330R"
			(at -36.275499 203.576501 0)
			(layer "F.Fab")
			(hide yes)
			(effects
				(font
					(size 1 1)
					(thickness 0.15)
				)
			)
		)
		(sheetname "/FPGA bank 14/")
		(sheetfile "fpga-bank-14.kicad_sch")
		(attr smd)
		(fp_rect
			(start -0.93 -0.47)
			(end 0.93 0.47)
			(stroke
				(width 0.05)
				(type solid)
			)
			(fill no)
			(layer "F.CrtYd")
		)
		(fp_rect
			(start -0.5 -0.25)
			(end 0.5 0.25)
			(stroke
				(width 0.15)
				(type solid)
			)
			(fill no)
			(layer "F.Fab")
		)
		(pad "1" smd roundrect
			(at -0.485 0 270)
			(size 0.59 0.64)
			(layers "F.Cu" "F.Mask" "F.Paste")
			(roundrect_rratio 0.25)
			(net 307 "Net-(D4-Pad2)")
			(pintype "passive")
		)
		(pad "2" smd roundrect
			(at 0.485 0 270)
			(size 0.59 0.64)
			(layers "F.Cu" "F.Mask" "F.Paste")
			(roundrect_rratio 0.25)
			(net 353 "Net-(Q4-D)")
			(pintype "passive")
		)
	)
	(footprint "antmicro-footprints:WSON-8_6x8x0.5mm_P1.27mm"
		(layer "F.Cu")
		(at 118.65 181.9 180)
		(property "Reference" "U3"
			(at -4.3 -3.2 180)
			(layer "F.SilkS")
			(effects
				(font
					(size 0.7 0.7)
					(thickness 0.15)
				)
				(justify left bottom)
			)
		)
		(property "Value" "S25FL128SAGNFI000"
			(at 0 4.3 180)
			(layer "F.Fab")
			(effects
				(font
					(size 0.7 0.7)
					(thickness 0.15)
				)
				(justify left bottom)
			)
		)
		(property "Datasheet" "https://www.farnell.com/datasheets/2309615.pdf"
			(at 0 0 180)
			(layer "F.Fab")
			(hide yes)
			(effects
				(font
					(size 1.27 1.27)
					(thickness 0.15)
				)
			)
		)
		(property "Author" "Antmicro"
			(at 237.3 363.8 0)
			(layer "F.Fab")
			(hide yes)
			(effects
				(font
					(size 1 1)
					(thickness 0.15)
				)
			)
		)
		(property "License" "Apache-2.0"
			(at 237.3 363.8 0)
			(layer "F.Fab")
			(hide yes)
			(effects
				(font
					(size 1 1)
					(thickness 0.15)
				)
			)
		)
		(property "MPN" "S25FL128SAGNFI000"
			(at 237.3 363.8 0)
			(layer "F.Fab")
			(hide yes)
			(effects
				(font
					(size 1 1)
					(thickness 0.15)
				)
			)
		)
		(property "Manufacturer" "Cypress Semiconductor"
			(at 237.3 363.8 0)
			(layer "F.Fab")
			(hide yes)
			(effects
				(font
					(size 1 1)
					(thickness 0.15)
				)
			)
		)
		(sheetname "/HyperRAM + QSPI Flash/")
		(sheetfile "hyperram-flash.kicad_sch")
		(attr smd)
		(fp_line
			(start 4.0005 3.2)
			(end -3.9995 3.2)
			(stroke
				(width 0.15)
				(type solid)
			)
			(layer "F.SilkS")
		)
		(fp_line
			(start 4 -3.2)
			(end -3.975 -3.2)
			(stroke
				(width 0.15)
				(type solid)
			)
			(layer "F.SilkS")
		)
		(fp_circle
			(center -4.2 -2.4)
			(end -4.149 -2.4)
			(stroke
				(width 0.15)
				(type solid)
			)
			(fill yes)
			(layer "F.SilkS")
		)
		(fp_rect
			(start -4.7 -3.25)
			(end 4.7 3.25)
			(stroke
				(width 0.05)
				(type solid)
			)
			(fill no)
			(layer "F.CrtYd")
		)
		(fp_line
			(start 3.9995 3.0005)
			(end -3.9995 3.0005)
			(stroke
				(width 0.15)
				(type solid)
			)
			(layer "F.Fab")
		)
		(fp_line
			(start 3.9995 -2.9995)
			(end 3.9995 3.0005)
			(stroke
				(width 0.15)
				(type solid)
			)
			(layer "F.Fab")
		)
		(fp_line
			(start -3.0015 -2.9995)
			(end 3.9995 -2.9995)
			(stroke
				(width 0.15)
				(type solid)
			)
			(layer "F.Fab")
		)
		(fp_line
			(start -3.0015 -2.9995)
			(end -3.9995 -1.9995)
			(stroke
				(width 0.15)
				(type solid)
			)
			(layer "F.Fab")
		)
		(fp_line
			(start -3.9995 3.0005)
			(end -3.9995 -1.9995)
			(stroke
				(width 0.15)
				(type solid)
			)
			(layer "F.Fab")
		)
		(pad "1" smd roundrect
			(at -3.9995 -1.9045 90)
			(size 0.4 1.3)
			(layers "F.Cu" "F.Mask" "F.Paste")
			(roundrect_rratio 0.25)
			(net 625 "/FPGA Config/FLASH.~{CS}")
			(pinfunction "~{CS}")
			(pintype "input")
		)
		(pad "2" smd roundrect
			(at -3.9995 -0.6355 90)
			(size 0.4 1.3)
			(layers "F.Cu" "F.Mask" "F.Paste")
			(roundrect_rratio 0.25)
			(net 363 "/HyperRAM + QSPI Flash/IO1")
			(pinfunction "SO/IO1")
			(pintype "bidirectional")
		)
		(pad "3" smd roundrect
			(at -3.9995 0.6345 90)
			(size 0.4 1.3)
			(layers "F.Cu" "F.Mask" "F.Paste")
			(roundrect_rratio 0.25)
			(net 361 "/HyperRAM + QSPI Flash/IO2")
			(pinfunction "~{WP}/IO2")
			(pintype "bidirectional")
		)
		(pad "4" smd roundrect
			(at -3.9995 1.9045 90)
			(size 0.4 1.3)
			(layers "F.Cu" "F.Mask" "F.Paste")
			(roundrect_rratio 0.25)
			(net 1 "GND")
			(pinfunction "V_{SS}")
			(pintype "power_in")
		)
		(pad "5" smd roundrect
			(at 3.9995 1.8755 90)
			(size 0.4 1.3)
			(layers "F.Cu" "F.Mask" "F.Paste")
			(roundrect_rratio 0.25)
			(net 362 "/HyperRAM + QSPI Flash/IO0")
			(pinfunction "SI/IO0")
			(pintype "bidirectional")
		)
		(pad "6" smd roundrect
			(at 3.9995 0.6035 90)
			(size 0.4 1.3)
			(layers "F.Cu" "F.Mask" "F.Paste")
			(roundrect_rratio 0.25)
			(net 630 "/FPGA Config/FLASH.SCK")
			(pinfunction "SCK")
			(pintype "input")
		)
		(pad "7" smd roundrect
			(at 3.9995 -0.6655 90)
			(size 0.4 1.3)
			(layers "F.Cu" "F.Mask" "F.Paste")
			(roundrect_rratio 0.25)
			(net 360 "/HyperRAM + QSPI Flash/IO3")
			(pinfunction "~{HOLD}/IO3")
			(pintype "bidirectional")
		)
		(pad "8" smd roundrect
			(at 3.9995 -1.9355 90)
			(size 0.4 1.3)
			(layers "F.Cu" "F.Mask" "F.Paste")
			(roundrect_rratio 0.25)
			(net 200 "+3V3")
			(pinfunction "V_{CC}")
			(pintype "power_in")
		)
		(pad "9" smd roundrect
			(at -0.0005 -0.0005 180)
			(size 4.8 4.65)
			(layers "F.Cu" "F.Mask" "F.Paste")
			(roundrect_rratio 0.05)
			(chamfer_ratio 0.1)
			(chamfer top_left)
			(net 393 "unconnected-(U3-EP-Pad9)")
			(pinfunction "EP")
			(pintype "no_connect")
		)
	)
	(footprint "antmicro-footprints:SOT-23-5"
		(layer "F.Cu")
		(at 81 151.1)
		(property "Reference" "U5"
			(at 0.4 2.7 0)
			(layer "F.SilkS")
			(effects
				(font
					(size 0.7 0.7)
					(thickness 0.15)
				)
				(justify left bottom)
			)
		)
		(property "Value" "NCP718BSN330T1G"
			(at 0.002 2.799 0)
			(layer "F.Fab")
			(effects
				(font
					(size 0.7 0.7)
					(thickness 0.15)
				)
				(justify left bottom)
			)
		)
		(property "Datasheet" "https://www.mouser.com/datasheet/2/308/NCP718_D-1224359.pdf"
			(at 0 0 0)
			(layer "F.Fab")
			(hide yes)
			(effects
				(font
					(size 1.27 1.27)
					(thickness 0.15)
				)
			)
		)
		(property "Author" "Antmicro"
			(at 0 0 0)
			(layer "F.Fab")
			(hide yes)
			(effects
				(font
					(size 1 1)
					(thickness 0.15)
				)
			)
		)
		(property "License" "Apache-2.0"
			(at 0 0 0)
			(layer "F.Fab")
			(hide yes)
			(effects
				(font
					(size 1 1)
					(thickness 0.15)
				)
			)
		)
		(property "MPN" "NCP718BSN330T1G"
			(at 0 0 0)
			(layer "F.Fab")
			(hide yes)
			(effects
				(font
					(size 1 1)
					(thickness 0.15)
				)
			)
		)
		(property "Manufacturer" "ON Semiconductor"
			(at 0 0 0)
			(layer "F.Fab")
			(hide yes)
			(effects
				(font
					(size 1 1)
					(thickness 0.15)
				)
			)
		)
		(sheetname "/Debug FTDI/")
		(sheetfile "debug-ftdi.kicad_sch")
		(attr smd)
		(fp_line
			(start -0.85 1.6)
			(end -0.85 1.301)
			(stroke
				(width 0.15)
				(type solid)
			)
			(layer "F.SilkS")
		)
		(fp_line
			(start -0.8 -1.6)
			(end -0.8 -1.3)
			(stroke
				(width 0.15)
				(type solid)
			)
			(layer "F.SilkS")
		)
		(fp_line
			(start -0.8 -1.6)
			(end -0.5 -1.6)
			(stroke
				(width 0.15)
				(type solid)
			)
			(layer "F.SilkS")
		)
		(fp_line
			(start -0.55 1.6)
			(end -0.85 1.6)
			(stroke
				(width 0.15)
				(type solid)
			)
			(layer "F.SilkS")
		)
		(fp_line
			(start 0.8 -1.6)
			(end 0.5 -1.6)
			(stroke
				(width 0.15)
				(type solid)
			)
			(layer "F.SilkS")
		)
		(fp_line
			(start 0.8 -1.3)
			(end 0.8 -1.6)
			(stroke
				(width 0.15)
				(type solid)
			)
			(layer "F.SilkS")
		)
		(fp_line
			(start 0.8 0.55)
			(end 0.8 -0.55)
			(stroke
				(width 0.15)
				(type solid)
			)
			(layer "F.SilkS")
		)
		(fp_line
			(start 0.8 1.3)
			(end 0.8 1.599)
			(stroke
				(width 0.15)
				(type solid)
			)
			(layer "F.SilkS")
		)
		(fp_line
			(start 0.8 1.599)
			(end 0.549 1.599)
			(stroke
				(width 0.15)
				(type solid)
			)
			(layer "F.SilkS")
		)
		(fp_circle
			(center -1.25 -1.5)
			(end -1.2 -1.5)
			(stroke
				(width 0.15)
				(type solid)
			)
			(fill yes)
			(layer "F.SilkS")
		)
		(fp_rect
			(start 1.9 -1.76)
			(end -1.9 1.75)
			(stroke
				(width 0.05)
				(type solid)
			)
			(fill no)
			(layer "F.CrtYd")
		)
		(fp_line
			(start -0.398 -1.526)
			(end -0.874 -1.05)
			(stroke
				(width 0.15)
				(type solid)
			)
			(layer "F.Fab")
		)
		(fp_rect
			(start 0.874 1.523)
			(end -0.873 -1.525)
			(stroke
				(width 0.15)
				(type solid)
			)
			(fill no)
			(layer "F.Fab")
		)
		(pad "1" smd rect
			(at -1.351 -0.951 270)
			(size 0.55 1)
			(layers "F.Cu" "F.Mask" "F.Paste")
			(net 2 "/Debug FTDI/VBUS")
			(pinfunction "VIN")
			(pintype "passive")
		)
		(pad "2" smd rect
			(at -1.351 0 270)
			(size 0.55 1)
			(layers "F.Cu" "F.Mask" "F.Paste")
			(net 1 "GND")
			(pinfunction "GND")
			(pintype "passive")
		)
		(pad "3" smd rect
			(at -1.351 0.949 270)
			(size 0.55 1)
			(layers "F.Cu" "F.Mask" "F.Paste")
			(net 2 "/Debug FTDI/VBUS")
			(pinfunction "EN")
			(pintype "passive")
		)
		(pad "4" smd rect
			(at 1.35 0.949 270)
			(size 0.55 1)
			(layers "F.Cu" "F.Mask" "F.Paste")
			(net 583 "unconnected-(U5-NC-Pad4)")
			(pinfunction "NC")
			(pintype "no_connect")
		)
		(pad "5" smd rect
			(at 1.35 -0.951 270)
			(size 0.55 1)
			(layers "F.Cu" "F.Mask" "F.Paste")
			(net 6 "/Debug FTDI/FTDI_3V3")
			(pinfunction "VOUT")
			(pintype "passive")
		)
	)
)
